(kicad_pcb
	(version 20260206)
	(generator "pcbnew")
	(generator_version "10.0")
	(general
		(thickness 1.6)
		(legacy_teardrops no)
	)
	(paper "A4")
	(title_block
		(title "Bryce Canyon_SCC_16316-1_OCP.brd")
		(comment 1 "Bryce Canyon / footprints 342-345 of 1561")
	)
	(layers
		(0 "F.Cu" signal "TOP")
		(4 "In1.Cu" signal "L2GND")
		(6 "In2.Cu" signal "L3")
		(8 "In3.Cu" signal "L4VCC")
		(10 "In4.Cu" signal "L5VCC")
		(12 "In5.Cu" signal "L6")
		(14 "In6.Cu" signal "L7GND")
		(2 "B.Cu" signal "BOTTOM")
		(9 "F.Adhes" user "F.Adhesive")
		(11 "B.Adhes" user "B.Adhesive")
		(13 "F.Paste" user "Package Geometry/Pastemask Top")
		(15 "B.Paste" user "Package Geometry/Pastemask Bottom")
		(5 "F.SilkS" user "Ref Des/Silkscreen Top")
		(7 "B.SilkS" user "Ref Des/Silkscreen Bottom")
		(1 "F.Mask" user "Board Geometry/Soldermask Top")
		(3 "B.Mask" user "Board Geometry/Soldermask Bottom")
		(17 "Dwgs.User" user "User.Drawings")
		(19 "Cmts.User" user "User.Comments")
		(21 "Eco1.User" user "User.Eco1")
		(23 "Eco2.User" user "User.Eco2")
		(25 "Edge.Cuts" user "Board Geometry/Outline")
		(27 "Margin" user)
		(31 "F.CrtYd" user "Package Geometry/Place Bound Top")
		(29 "B.CrtYd" user "Package Geometry/Place Bound Bottom")
		(35 "F.Fab" user "Ref Des/Assembly Top")
		(33 "B.Fab" user "Ref Des/Assembly Bottom")
	)
	(footprint ""
		(layer "F.Cu")
		(at 191.85382 -54.4068 90)
		(property "Reference" "R227"
			(at 0 0 90)
			(layer "F.SilkS")
			(hide yes)
			(effects
				(font
					(size 1.27 1.27)
				)
			)
		)
		(property "Value" "10KR2F-2-GP"
			(at 0.064008 -3.993896 90)
			(unlocked yes)
			(layer "F.Fab")
			(hide yes)
			(effects
				(font
					(size 1.016 1.016)
					(thickness 0.1524)
				)
			)
		)
		(property "Device Type" "R402H16"
			(at 0.064008 -5.517896 90)
			(unlocked yes)
			(layer "F.Fab")
			(hide yes)
			(effects
				(font
					(size 1.016 1.016)
					(thickness 0.1524)
				)
			)
		)
		(duplicate_pad_numbers_are_jumpers no)
		(fp_line
			(start 0.508 -0.9398)
			(end -0.508 -0.9398)
			(stroke
				(width 0.1524)
				(type default)
			)
			(layer "F.SilkS")
		)
		(fp_line
			(start -0.508 -0.9398)
			(end -0.508 0.9398)
			(stroke
				(width 0.1524)
				(type default)
			)
			(layer "F.SilkS")
		)
		(fp_rect
			(start -0.508 0.9398)
			(end 0.508 -0.9398)
			(stroke
				(width 0)
				(type default)
			)
			(fill no)
			(layer "F.CrtYd")
		)
		(fp_rect
			(start -0.508 0.9398)
			(end 0.508 -0.9398)
			(stroke
				(width 0)
				(type default)
			)
			(fill no)
			(layer "F.Fab")
		)
		(pad "1" smd custom
			(at 0 -0.4445 90)
			(size 0.1397 0.1397)
			(layers "F.Cu" "F.Mask" "F.Paste")
			(net "XM_ADDR_8")
			(options
				(clearance outline)
				(anchor circle)
			)
			(primitives
				(gr_poly
					(pts
						(arc
							(start -0.1778 -0.2794)
							(mid -0.249642 -0.249642)
							(end -0.2794 -0.1778)
						)
						(arc
							(start -0.2794 0.1778)
							(mid -0.249642 0.249642)
							(end -0.1778 0.2794)
						)
						(arc
							(start 0.1778 0.2794)
							(mid 0.249642 0.249642)
							(end 0.2794 0.1778)
						)
						(arc
							(start 0.2794 -0.1778)
							(mid 0.249642 -0.249642)
							(end 0.1778 -0.2794)
						)
					)
					(width 0)
					(fill yes)
				)
			)
		)
		(pad "2" smd custom
			(at 0 0.4445 90)
			(size 0.1397 0.1397)
			(layers "F.Cu" "F.Mask" "F.Paste")
			(net "GND")
			(options
				(clearance outline)
				(anchor circle)
			)
			(primitives
				(gr_poly
					(pts
						(arc
							(start -0.1778 -0.2794)
							(mid -0.249642 -0.249642)
							(end -0.2794 -0.1778)
						)
						(arc
							(start -0.2794 0.1778)
							(mid -0.249642 0.249642)
							(end -0.1778 0.2794)
						)
						(arc
							(start 0.1778 0.2794)
							(mid 0.249642 0.249642)
							(end 0.2794 0.1778)
						)
						(arc
							(start 0.2794 -0.1778)
							(mid 0.249642 -0.249642)
							(end 0.1778 -0.2794)
						)
					)
					(width 0)
					(fill yes)
				)
			)
		)
	)
	(footprint ""
		(layer "F.Cu")
		(at 155.9687 -89.7636 -90)
		(property "Reference" "R333"
			(at 0 0 270)
			(layer "F.SilkS")
			(hide yes)
			(effects
				(font
					(size 1.27 1.27)
				)
			)
		)
		(property "Value" "4K7R2F-GP"
			(at 0.064008 -3.993896 270)
			(unlocked yes)
			(layer "F.Fab")
			(hide yes)
			(effects
				(font
					(size 1.016 1.016)
					(thickness 0.1524)
				)
			)
		)
		(property "Device Type" "R402H16"
			(at 0.064008 -5.517896 270)
			(unlocked yes)
			(layer "F.Fab")
			(hide yes)
			(effects
				(font
					(size 1.016 1.016)
					(thickness 0.1524)
				)
			)
		)
		(duplicate_pad_numbers_are_jumpers no)
		(fp_line
			(start -0.508 -0.9398)
			(end -0.508 0.9398)
			(stroke
				(width 0.1524)
				(type default)
			)
			(layer "F.SilkS")
		)
		(fp_line
			(start 0.508 -0.9398)
			(end -0.508 -0.9398)
			(stroke
				(width 0.1524)
				(type default)
			)
			(layer "F.SilkS")
		)
		(fp_rect
			(start -0.508 0.9398)
			(end 0.508 -0.9398)
			(stroke
				(width 0)
				(type default)
			)
			(fill no)
			(layer "F.CrtYd")
		)
		(fp_rect
			(start -0.508 0.9398)
			(end 0.508 -0.9398)
			(stroke
				(width 0)
				(type default)
			)
			(fill no)
			(layer "F.Fab")
		)
		(pad "1" smd custom
			(at 0 -0.4445 270)
			(size 0.1397 0.1397)
			(layers "F.Cu" "F.Mask" "F.Paste")
			(net "VOL_SEN1_ADDR")
			(options
				(clearance outline)
				(anchor circle)
			)
			(primitives
				(gr_poly
					(pts
						(arc
							(start -0.1778 -0.2794)
							(mid -0.249642 -0.249642)
							(end -0.2794 -0.1778)
						)
						(arc
							(start -0.2794 0.1778)
							(mid -0.249642 0.249642)
							(end -0.1778 0.2794)
						)
						(arc
							(start 0.1778 0.2794)
							(mid 0.249642 0.249642)
							(end 0.2794 0.1778)
						)
						(arc
							(start 0.2794 -0.1778)
							(mid 0.249642 -0.249642)
							(end 0.1778 -0.2794)
						)
					)
					(width 0)
					(fill yes)
				)
			)
		)
		(pad "2" smd custom
			(at 0 0.4445 270)
			(size 0.1397 0.1397)
			(layers "F.Cu" "F.Mask" "F.Paste")
			(net "GND")
			(options
				(clearance outline)
				(anchor circle)
			)
			(primitives
				(gr_poly
					(pts
						(arc
							(start -0.1778 -0.2794)
							(mid -0.249642 -0.249642)
							(end -0.2794 -0.1778)
						)
						(arc
							(start -0.2794 0.1778)
							(mid -0.249642 0.249642)
							(end -0.1778 0.2794)
						)
						(arc
							(start 0.1778 0.2794)
							(mid 0.249642 0.249642)
							(end 0.2794 0.1778)
						)
						(arc
							(start 0.2794 -0.1778)
							(mid 0.249642 -0.249642)
							(end 0.1778 -0.2794)
						)
					)
					(width 0)
					(fill yes)
				)
			)
		)
	)
	(footprint ""
		(layer "F.Cu")
		(at 13.9446 -53.2638 -90)
		(property "Reference" "U5"
			(at 0 0 270)
			(layer "F.SilkS")
			(hide yes)
			(effects
				(font
					(size 1.27 1.27)
				)
			)
		)
		(property "Value" "ADM1278-2ACPZ-RL-1-GP"
			(at -4.7625 -7.4422 270)
			(unlocked yes)
			(layer "F.Fab")
			(hide yes)
			(effects
				(font
					(size 1.016 1.016)
					(thickness 0.1524)
				)
			)
		)
		(property "Device Type" "QFN32-G3D45-UH32"
			(at -4.7625 -8.9662 270)
			(unlocked yes)
			(layer "F.Fab")
			(hide yes)
			(effects
				(font
					(size 1.016 1.016)
					(thickness 0.1524)
				)
			)
		)
		(duplicate_pad_numbers_are_jumpers no)
		(fp_line
			(start -0.250698 4.0513)
			(end -0.250698 3.2893)
			(stroke
				(width 0.1524)
				(type default)
			)
			(layer "F.SilkS")
		)
		(fp_line
			(start -3.5179 3.5179)
			(end -2.2479 3.5179)
			(stroke
				(width 0.1524)
				(type default)
			)
			(layer "F.SilkS")
		)
		(fp_line
			(start 3.5179 3.5179)
			(end 2.2479 3.5179)
			(stroke
				(width 0.1524)
				(type default)
			)
			(layer "F.SilkS")
		)
		(fp_line
			(start -3.5179 2.2479)
			(end -3.5179 3.5179)
			(stroke
				(width 0.1524)
				(type default)
			)
			(layer "F.SilkS")
		)
		(fp_line
			(start 3.5179 2.2479)
			(end 3.5179 3.5179)
			(stroke
				(width 0.1524)
				(type default)
			)
			(layer "F.SilkS")
		)
		(fp_line
			(start 3.7973 1.749552)
			(end 3.2893 1.749552)
			(stroke
				(width 0.1524)
				(type default)
			)
			(layer "F.SilkS")
		)
		(fp_line
			(start -3.7973 1.24968)
			(end -3.2893 1.24968)
			(stroke
				(width 0.1524)
				(type default)
			)
			(layer "F.SilkS")
		)
		(fp_line
			(start 4.0513 -0.749808)
			(end 3.2893 -0.749808)
			(stroke
				(width 0.1524)
				(type default)
			)
			(layer "F.SilkS")
		)
		(fp_line
			(start -4.0513 -1.24968)
			(end -3.2893 -1.24968)
			(stroke
				(width 0.1524)
				(type default)
			)
			(layer "F.SilkS")
		)
		(fp_line
			(start -3.5179 -2.2479)
			(end -3.5179 -3.5179)
			(stroke
				(width 0.1524)
				(type default)
			)
			(layer "F.SilkS")
		)
		(fp_line
			(start -3.5179 -3.5179)
			(end -2.2479 -3.5179)
			(stroke
				(width 0.1524)
				(type default)
			)
			(layer "F.SilkS")
		)
		(fp_line
			(start -0.250698 -3.7973)
			(end -0.250698 -3.2893)
			(stroke
				(width 0.1524)
				(type default)
			)
			(layer "F.SilkS")
		)
		(fp_poly
			(pts
				(xy 2.2479 -3.5179) (xy 3.5179 -2.2479) (xy 3.5179 -3.5179)
			)
			(stroke
				(width 0)
				(type default)
			)
			(fill yes)
			(layer "F.SilkS")
		)
		(fp_rect
			(start -2.5019 2.5019)
			(end 2.5019 -2.5019)
			(stroke
				(width 0)
				(type default)
			)
			(fill no)
			(layer "F.CrtYd")
		)
		(fp_poly
			(pts
				(xy -3.5179 3.5179) (xy -3.5179 -3.5179) (xy 3.5179 -3.5179) (xy 3.5179 3.5179) (xy -2.49682 3.5179)
				(xy -2.49682 2.5019) (xy 2.5019 2.5019) (xy 2.5019 -2.5019) (xy -2.5019 -2.5019) (xy -2.5019 3.5179)
			)
			(stroke
				(width 0)
				(type default)
			)
			(fill no)
			(layer "F.CrtYd")
		)
		(fp_rect
			(start -3.5179 3.5179)
			(end 3.5179 -3.5179)
			(stroke
				(width 0)
				(type default)
			)
			(fill no)
			(layer "F.Fab")
		)
		(pad "1" smd rect
			(at 1.75006 -2.5527 270)
			(size 0.3048 0.9144)
			(layers "F.Cu" "F.Mask" "F.Paste")
			(net "MB0_PSET_R")
		)
		(pad "2" smd rect
			(at 1.249934 -2.4765 270)
			(size 0.3048 1.0668)
			(layers "F.Cu" "F.Mask" "F.Paste")
			(net "MB0_VCAP_R")
		)
		(pad "3" smd rect
			(at 0.750062 -2.4765 270)
			(size 0.3048 1.0668)
			(layers "F.Cu" "F.Mask" "F.Paste")
			(net "MB0_ISET_R")
		)
		(pad "4" smd rect
			(at 0.249936 -2.4765 270)
			(size 0.3048 1.0668)
			(layers "F.Cu" "F.Mask" "F.Paste")
			(net "MB0_ISTART_R")
		)
		(pad "5" smd rect
			(at -0.249936 -2.4765 270)
			(size 0.3048 1.0668)
			(layers "F.Cu" "F.Mask" "F.Paste")
			(net "MB0_TIME_R")
		)
		(pad "6" smd rect
			(at -0.750062 -2.4765 270)
			(size 0.3048 1.0668)
			(layers "F.Cu" "F.Mask" "F.Paste")
			(net "Net_696")
		)
		(pad "7" smd rect
			(at -1.249934 -2.4765 270)
			(size 0.3048 1.0668)
			(layers "F.Cu" "F.Mask" "F.Paste")
			(net "MB0_CM_ADR1_R")
		)
		(pad "8" smd rect
			(at -1.75006 -2.5527 270)
			(size 0.3048 0.9144)
			(layers "F.Cu" "F.Mask" "F.Paste")
			(net "MB0_CM_ADR2_R")
		)
		(pad "9" smd rect
			(at -2.5527 -1.75006 270)
			(size 0.9144 0.3048)
			(layers "F.Cu" "F.Mask" "F.Paste")
			(net "MB0_SPISS_PD")
		)
		(pad "10" smd rect
			(at -2.4765 -1.249934 270)
			(size 1.0668 0.3048)
			(layers "F.Cu" "F.Mask" "F.Paste")
			(net "Net_700")
		)
		(pad "11" smd rect
			(at -2.4765 -0.750062 270)
			(size 1.0668 0.3048)
			(layers "F.Cu" "F.Mask" "F.Paste")
			(net "Net_699")
		)
		(pad "12" smd rect
			(at -2.4765 -0.249936 270)
			(size 1.0668 0.3048)
			(layers "F.Cu" "F.Mask" "F.Paste")
			(net "MB0_HS_ENABLE")
		)
		(pad "13" smd rect
			(at -2.4765 0.249936 270)
			(size 1.0668 0.3048)
			(layers "F.Cu" "F.Mask" "F.Paste")
			(net "Net_698")
		)
		(pad "14" smd rect
			(at -2.4765 0.750062 270)
			(size 1.0668 0.3048)
			(layers "F.Cu" "F.Mask" "F.Paste")
			(net "Net_697")
		)
		(pad "15" smd rect
			(at -2.4765 1.249934 270)
			(size 1.0668 0.3048)
			(layers "F.Cu" "F.Mask" "F.Paste")
			(net "HSW_SDA_2")
		)
		(pad "16" smd rect
			(at -2.5527 1.75006 270)
			(size 0.9144 0.3048)
			(layers "F.Cu" "F.Mask" "F.Paste")
			(net "HSW_SCL_2")
		)
		(pad "17" smd rect
			(at -1.75006 2.5527 270)
			(size 0.3048 0.9144)
			(layers "F.Cu" "F.Mask" "F.Paste")
			(net "MB0_RETRY_R")
		)
		(pad "18" smd rect
			(at -1.249934 2.4765 270)
			(size 0.3048 1.0668)
			(layers "F.Cu" "F.Mask" "F.Paste")
			(net "P12V_SCC_PGOOD")
		)
		(pad "19" smd rect
			(at -0.750062 2.4765 270)
			(size 0.3048 1.0668)
			(layers "F.Cu" "F.Mask" "F.Paste")
			(net "Net_701")
		)
		(pad "20" smd rect
			(at -0.249936 2.4765 270)
			(size 0.3048 1.0668)
			(layers "F.Cu" "F.Mask" "F.Paste")
			(net "MB0_CM_VOUT_R")
		)
		(pad "21" smd rect
			(at 0.249936 2.4765 270)
			(size 0.3048 1.0668)
			(layers "F.Cu" "F.Mask" "F.Paste")
			(net "MB0_P12V_PWGIN_R")
		)
		(pad "22" smd rect
			(at 0.750062 2.4765 270)
			(size 0.3048 1.0668)
			(layers "F.Cu" "F.Mask" "F.Paste")
			(net "AGND_CURRENT_MON")
		)
		(pad "23" smd rect
			(at 1.249934 2.4765 270)
			(size 0.3048 1.0668)
			(layers "F.Cu" "F.Mask" "F.Paste")
			(net "GND")
		)
		(pad "24" smd rect
			(at 1.75006 2.5527 270)
			(size 0.3048 0.9144)
			(layers "F.Cu" "F.Mask" "F.Paste")
			(net "MB0_CM_GATE")
		)
		(pad "25" smd rect
			(at 2.5527 1.75006 270)
			(size 0.9144 0.3048)
			(layers "F.Cu" "F.Mask" "F.Paste")
			(net "MB0_TEMP")
		)
		(pad "26" smd rect
			(at 2.4765 1.249934 270)
			(size 1.0668 0.3048)
			(layers "F.Cu" "F.Mask" "F.Paste")
			(net "MB0_CM_SENSE_N")
		)
		(pad "27" smd rect
			(at 2.4765 0.750062 270)
			(size 1.0668 0.3048)
			(layers "F.Cu" "F.Mask" "F.Paste")
			(net "MB0_HS_SENSE_N")
		)
		(pad "28" smd rect
			(at 2.4765 0.249936 270)
			(size 1.0668 0.3048)
			(layers "F.Cu" "F.Mask" "F.Paste")
			(net "MB0_HS_SENSE_P")
		)
		(pad "29" smd rect
			(at 2.4765 -0.249936 270)
			(size 1.0668 0.3048)
			(layers "F.Cu" "F.Mask" "F.Paste")
			(net "MB0_CM_SENSE_P")
		)
		(pad "30" smd rect
			(at 2.4765 -0.750062 270)
			(size 1.0668 0.3048)
			(layers "F.Cu" "F.Mask" "F.Paste")
			(net "MB0_VCC")
		)
		(pad "31" smd rect
			(at 2.4765 -1.249934 270)
			(size 1.0668 0.3048)
			(layers "F.Cu" "F.Mask" "F.Paste")
			(net "MB0_CM_UV_R")
		)
		(pad "32" smd rect
			(at 2.5527 -1.75006 270)
			(size 0.9144 0.3048)
			(layers "F.Cu" "F.Mask" "F.Paste")
			(net "MB0_CM_OV_R")
		)
		(pad "33" smd rect
			(at 0 0 270)
			(size 3.4544 3.4544)
			(layers "F.Cu" "F.Mask" "F.Paste")
			(net "AGND_CURRENT_MON")
		)
	)
	(footprint ""
		(layer "F.Cu")
		(at 50.0126 -46.482 90)
		(property "Reference" "Q7"
			(at 0 0 90)
			(layer "F.SilkS")
			(hide yes)
			(effects
				(font
					(size 1.27 1.27)
				)
			)
		)
		(property "Value" "CSD87350Q5D-1-GP"
			(at -4.064 -3.3782 90)
			(unlocked yes)
			(layer "F.Fab")
			(hide yes)
			(effects
				(font
					(size 1.016 1.016)
					(thickness 0.1524)
				)
			)
		)
		(property "Device Type" "PPAK-8P-G510321H62"
			(at -4.064 -4.9022 90)
			(unlocked yes)
			(layer "F.Fab")
			(hide yes)
			(effects
				(font
					(size 1.016 1.016)
					(thickness 0.1524)
				)
			)
		)
		(duplicate_pad_numbers_are_jumpers no)
		(fp_line
			(start -2.0447 -4.0132)
			(end -3.0607 -4.0132)
			(stroke
				(width 0.1524)
				(type default)
			)
			(layer "F.SilkS")
		)
		(fp_line
			(start -3.0607 -4.0132)
			(end -3.0607 -2.9972)
			(stroke
				(width 0.1524)
				(type default)
			)
			(layer "F.SilkS")
		)
		(fp_line
			(start 3.0607 2.9972)
			(end 3.0607 4.0132)
			(stroke
				(width 0.1524)
				(type default)
			)
			(layer "F.SilkS")
		)
		(fp_line
			(start -3.0607 2.9972)
			(end -3.0607 4.0132)
			(stroke
				(width 0.1524)
				(type default)
			)
			(layer "F.SilkS")
		)
		(fp_line
			(start -1.905 3.761994)
			(end -1.905 4.269994)
			(stroke
				(width 0.1524)
				(type default)
			)
			(layer "F.SilkS")
		)
		(fp_line
			(start 3.0607 4.0132)
			(end 2.0447 4.0132)
			(stroke
				(width 0.1524)
				(type default)
			)
			(layer "F.SilkS")
		)
		(fp_line
			(start -3.0607 4.0132)
			(end -2.0447 4.0132)
			(stroke
				(width 0.1524)
				(type default)
			)
			(layer "F.SilkS")
		)
		(fp_poly
			(pts
				(xy 2.0447 -4.0132) (xy 3.0607 -4.0132) (xy 3.0607 -2.9972)
			)
			(stroke
				(width 0)
				(type default)
			)
			(fill yes)
			(layer "F.SilkS")
		)
		(fp_rect
			(start -2.5019 2.9972)
			(end 2.5019 -2.9972)
			(stroke
				(width 0)
				(type default)
			)
			(fill no)
			(layer "F.CrtYd")
		)
		(fp_poly
			(pts
				(xy -3.0607 4.0132) (xy -3.0607 -4.0132) (xy 3.0607 -4.0132) (xy 3.0607 4.0132) (xy 0.00254 4.0132)
				(xy 0.00254 2.9972) (xy 2.5019 2.9972) (xy 2.5019 -2.9972) (xy -2.5019 -2.9972) (xy -2.5019 2.9972)
				(xy -0.00254 2.9972) (xy -0.00254 4.0132)
			)
			(stroke
				(width 0)
				(type default)
			)
			(fill no)
			(layer "F.CrtYd")
		)
		(fp_rect
			(start -3.0607 4.0132)
			(end 3.0607 -4.0132)
			(stroke
				(width 0)
				(type default)
			)
			(fill no)
			(layer "F.Fab")
		)
		(pad "1" smd rect
			(at 1.27 -2.822194 90)
			(size 1.905 1.3716)
			(layers "F.Cu" "F.Mask" "F.Paste")
			(net "P12V_STBY_VIN_Q7")
		)
		(pad "2" smd rect
			(at 0.635 -2.822194 90)
			(size 0.0254 0.0254)
			(layers "F.Cu" "F.Mask" "F.Paste")
			(net "P12V_STBY_VIN_Q7")
		)
		(pad "3" smd rect
			(at -0.635 -2.822194 90)
			(size 0.635 1.3716)
			(layers "F.Cu" "F.Mask" "F.Paste")
			(net "P0V9_TG")
		)
		(pad "4" smd rect
			(at -1.905 -2.822194 90)
			(size 0.635 1.3716)
			(layers "F.Cu" "F.Mask" "F.Paste")
			(net "P0V9_SW")
		)
		(pad "5" smd rect
			(at -1.905 2.822194 90)
			(size 0.635 1.3716)
			(layers "F.Cu" "F.Mask" "F.Paste")
			(net "P0V9_BG")
		)
		(pad "6" smd rect
			(at -0.635 2.822194 90)
			(size 0.635 1.3716)
			(layers "F.Cu" "F.Mask" "F.Paste")
			(net "P0V9_VSW")
		)
		(pad "7" smd rect
			(at 0.635 2.822194 90)
			(size 0.635 1.3716)
			(layers "F.Cu" "F.Mask" "F.Paste")
			(net "P0V9_VSW")
		)
		(pad "8" smd rect
			(at 1.905 2.822194 90)
			(size 0.635 1.3716)
			(layers "F.Cu" "F.Mask" "F.Paste")
			(net "P0V9_VSW")
		)
		(pad "9" smd rect
			(at 0 0 90)
			(size 5.1054 3.2004)
			(layers "F.Cu" "F.Mask" "F.Paste")
			(net "GND")
		)
	)
)
